(kicad_pcb
	(version 20260206)
	(generator "pcbnew")
	(generator_version "10.0")
	(general
		(thickness 1.6)
		(legacy_teardrops no)
	)
	(paper "A4")
	(title_block
		(title "04192023_DAF0TMB3IC0_F0TG_MB_C_brd_V02_OCP.brd")
		(comment 1 "Grand Teton / footprints 590-596 of 8354")
	)
	(layers
		(0 "F.Cu" signal "TOP")
		(4 "In1.Cu" signal "GND")
		(6 "In2.Cu" signal "IN1")
		(8 "In3.Cu" signal "GND1")
		(10 "In4.Cu" signal "IN2")
		(12 "In5.Cu" signal "GND2")
		(14 "In6.Cu" signal "IN3")
		(16 "In7.Cu" signal "GND3")
		(18 "In8.Cu" signal "VCC")
		(20 "In9.Cu" signal "VCC1")
		(22 "In10.Cu" signal "GND4")
		(24 "In11.Cu" signal "IN4")
		(26 "In12.Cu" signal "GND5")
		(28 "In13.Cu" signal "IN5")
		(30 "In14.Cu" signal "GND6")
		(32 "In15.Cu" signal "IN6")
		(34 "In16.Cu" signal "GND7")
		(2 "B.Cu" signal "BOTTOM")
		(9 "F.Adhes" user "F.Adhesive")
		(11 "B.Adhes" user "B.Adhesive")
		(13 "F.Paste" user "Package Geometry/Pastemask Top")
		(15 "B.Paste" user "Package Geometry/Pastemask Bottom")
		(5 "F.SilkS" user "Ref Des/Silkscreen Top")
		(7 "B.SilkS" user "Ref Des/Silkscreen Bottom")
		(1 "F.Mask" user "Board Geometry/Soldermask Top")
		(3 "B.Mask" user "Board Geometry/Soldermask Bottom")
		(17 "Dwgs.User" user "User.Drawings")
		(19 "Cmts.User" user "User.Comments")
		(21 "Eco1.User" user "User.Eco1")
		(23 "Eco2.User" user "User.Eco2")
		(25 "Edge.Cuts" user "Board Geometry/Outline")
		(27 "Margin" user)
		(31 "F.CrtYd" user "Package Geometry/Place Bound Top")
		(29 "B.CrtYd" user "Package Geometry/Place Bound Bottom")
		(35 "F.Fab" user "Ref Des/Assembly Top")
		(33 "B.Fab" user "Ref Des/Assembly Bottom")
	)
	(footprint ""
		(layer "F.Cu")
		(at 277.608792 -121.37517 -90)
		(property "Reference" "R6212"
			(at 0 0 270)
			(layer "F.SilkS")
			(hide yes)
			(effects
				(font
					(size 1.27 1.27)
				)
			)
		)
		(property "Value" ""
			(at 0 0 270)
			(layer "F.Fab")
			(effects
				(font
					(size 1.27 1.27)
				)
			)
		)
		(duplicate_pad_numbers_are_jumpers no)
		(fp_line
			(start -0.7874 0.4064)
			(end -0.7874 -0.4064)
			(stroke
				(width 0.1524)
				(type default)
			)
			(layer "F.SilkS")
		)
		(fp_line
			(start 0.7874 0.4064)
			(end -0.7874 0.4064)
			(stroke
				(width 0.1524)
				(type default)
			)
			(layer "F.SilkS")
		)
		(fp_line
			(start -0.7874 -0.4064)
			(end 0.7874 -0.4064)
			(stroke
				(width 0.1524)
				(type default)
			)
			(layer "F.SilkS")
		)
		(fp_line
			(start 0.7874 -0.4064)
			(end 0.7874 0.4064)
			(stroke
				(width 0.1524)
				(type default)
			)
			(layer "F.SilkS")
		)
		(fp_line
			(start -0.67945 0.3048)
			(end -0.67945 -0.305054)
			(stroke
				(width 0.1)
				(type default)
			)
			(layer "F.Fab")
		)
		(fp_line
			(start -0.12065 0.3048)
			(end -0.67945 0.3048)
			(stroke
				(width 0.1)
				(type default)
			)
			(layer "F.Fab")
		)
		(fp_line
			(start 0.120396 0.3048)
			(end 0.120396 0.2794)
			(stroke
				(width 0.1)
				(type default)
			)
			(layer "F.Fab")
		)
		(fp_line
			(start 0.67945 0.3048)
			(end 0.120396 0.3048)
			(stroke
				(width 0.1)
				(type default)
			)
			(layer "F.Fab")
		)
		(fp_line
			(start -0.12065 0.2794)
			(end -0.12065 0.3048)
			(stroke
				(width 0.1)
				(type default)
			)
			(layer "F.Fab")
		)
		(fp_line
			(start 0.120396 0.2794)
			(end -0.12065 0.2794)
			(stroke
				(width 0.1)
				(type default)
			)
			(layer "F.Fab")
		)
		(fp_line
			(start -0.12065 -0.2794)
			(end 0.12065 -0.2794)
			(stroke
				(width 0.1)
				(type default)
			)
			(layer "F.Fab")
		)
		(fp_line
			(start 0.12065 -0.2794)
			(end 0.12065 -0.3048)
			(stroke
				(width 0.1)
				(type default)
			)
			(layer "F.Fab")
		)
		(fp_line
			(start 0.12065 -0.3048)
			(end 0.67945 -0.3048)
			(stroke
				(width 0.1)
				(type default)
			)
			(layer "F.Fab")
		)
		(fp_line
			(start 0.67945 -0.3048)
			(end 0.67945 0.3048)
			(stroke
				(width 0.1)
				(type default)
			)
			(layer "F.Fab")
		)
		(fp_line
			(start -0.67945 -0.305054)
			(end -0.12065 -0.305054)
			(stroke
				(width 0.1)
				(type default)
			)
			(layer "F.Fab")
		)
		(fp_line
			(start -0.12065 -0.305054)
			(end -0.12065 -0.2794)
			(stroke
				(width 0.1)
				(type default)
			)
			(layer "F.Fab")
		)
		(pad "1" smd circle
			(at -0.40005 0 270)
			(size 0 0)
			(layers "F.Cu" "F.Mask" "F.Paste")
			(net "P3V3_AUX")
		)
		(pad "2" smd circle
			(at 0.40005 0 270)
			(size 0 0)
			(layers "F.Cu" "F.Mask" "F.Paste")
			(net "SMB_USB_CPU0_HUB1_SDA")
		)
	)
	(footprint ""
		(layer "F.Cu")
		(at 365.09579 -393.86256)
		(property "Reference" "R1111"
			(at 0 0 0)
			(layer "F.SilkS")
			(hide yes)
			(effects
				(font
					(size 1.27 1.27)
				)
			)
		)
		(property "Value" ""
			(at 0 0 0)
			(layer "F.Fab")
			(effects
				(font
					(size 1.27 1.27)
				)
			)
		)
		(duplicate_pad_numbers_are_jumpers no)
		(fp_line
			(start -0.32512 -0.175006)
			(end 0.32512 -0.175006)
			(stroke
				(width 0.1)
				(type default)
			)
			(layer "F.Fab")
		)
		(fp_line
			(start -0.32512 0.175006)
			(end -0.32512 -0.175006)
			(stroke
				(width 0.1)
				(type default)
			)
			(layer "F.Fab")
		)
		(fp_line
			(start 0.32512 -0.175006)
			(end 0.32512 0.175006)
			(stroke
				(width 0.1)
				(type default)
			)
			(layer "F.Fab")
		)
		(fp_line
			(start 0.32512 0.175006)
			(end -0.32512 0.175006)
			(stroke
				(width 0.1)
				(type default)
			)
			(layer "F.Fab")
		)
		(pad "1" smd rect
			(at -0.2667 0)
			(size 0.3048 0.381)
			(layers "F.Cu" "F.Mask" "F.Paste")
			(net "P1V8_CPU0_RT_1D")
		)
		(pad "2" smd rect
			(at 0.2667 0 180)
			(size 0.3048 0.381)
			(layers "F.Cu" "F.Mask" "F.Paste")
			(net "GPIO2_RT_CPU0_P3")
		)
	)
	(footprint ""
		(layer "F.Cu")
		(at 264.478516 -131.067556 180)
		(property "Reference" "R811"
			(at 0 0 180)
			(layer "F.SilkS")
			(hide yes)
			(effects
				(font
					(size 1.27 1.27)
				)
			)
		)
		(property "Value" ""
			(at 0 0 180)
			(layer "F.Fab")
			(effects
				(font
					(size 1.27 1.27)
				)
			)
		)
		(duplicate_pad_numbers_are_jumpers no)
		(fp_line
			(start 0.7874 0.4064)
			(end -0.7874 0.4064)
			(stroke
				(width 0.1524)
				(type default)
			)
			(layer "F.SilkS")
		)
		(fp_line
			(start 0.7874 -0.4064)
			(end 0.7874 0.4064)
			(stroke
				(width 0.1524)
				(type default)
			)
			(layer "F.SilkS")
		)
		(fp_line
			(start -0.7874 0.4064)
			(end -0.7874 -0.4064)
			(stroke
				(width 0.1524)
				(type default)
			)
			(layer "F.SilkS")
		)
		(fp_line
			(start -0.7874 -0.4064)
			(end 0.7874 -0.4064)
			(stroke
				(width 0.1524)
				(type default)
			)
			(layer "F.SilkS")
		)
		(fp_line
			(start 0.67945 0.3048)
			(end 0.120396 0.3048)
			(stroke
				(width 0.1)
				(type default)
			)
			(layer "F.Fab")
		)
		(fp_line
			(start 0.67945 -0.3048)
			(end 0.67945 0.3048)
			(stroke
				(width 0.1)
				(type default)
			)
			(layer "F.Fab")
		)
		(fp_line
			(start 0.12065 -0.2794)
			(end 0.12065 -0.3048)
			(stroke
				(width 0.1)
				(type default)
			)
			(layer "F.Fab")
		)
		(fp_line
			(start 0.12065 -0.3048)
			(end 0.67945 -0.3048)
			(stroke
				(width 0.1)
				(type default)
			)
			(layer "F.Fab")
		)
		(fp_line
			(start 0.120396 0.3048)
			(end 0.120396 0.2794)
			(stroke
				(width 0.1)
				(type default)
			)
			(layer "F.Fab")
		)
		(fp_line
			(start 0.120396 0.2794)
			(end -0.12065 0.2794)
			(stroke
				(width 0.1)
				(type default)
			)
			(layer "F.Fab")
		)
		(fp_line
			(start -0.12065 0.3048)
			(end -0.67945 0.3048)
			(stroke
				(width 0.1)
				(type default)
			)
			(layer "F.Fab")
		)
		(fp_line
			(start -0.12065 0.2794)
			(end -0.12065 0.3048)
			(stroke
				(width 0.1)
				(type default)
			)
			(layer "F.Fab")
		)
		(fp_line
			(start -0.12065 -0.2794)
			(end 0.12065 -0.2794)
			(stroke
				(width 0.1)
				(type default)
			)
			(layer "F.Fab")
		)
		(fp_line
			(start -0.12065 -0.305054)
			(end -0.12065 -0.2794)
			(stroke
				(width 0.1)
				(type default)
			)
			(layer "F.Fab")
		)
		(fp_line
			(start -0.67945 0.3048)
			(end -0.67945 -0.305054)
			(stroke
				(width 0.1)
				(type default)
			)
			(layer "F.Fab")
		)
		(fp_line
			(start -0.67945 -0.305054)
			(end -0.12065 -0.305054)
			(stroke
				(width 0.1)
				(type default)
			)
			(layer "F.Fab")
		)
		(pad "1" smd circle
			(at -0.40005 0 180)
			(size 0 0)
			(layers "F.Cu" "F.Mask" "F.Paste")
			(net "PVDD18_S5_P0")
		)
		(pad "2" smd circle
			(at 0.40005 0 180)
			(size 0 0)
			(layers "F.Cu" "F.Mask" "F.Paste")
			(net "SPI_CPU0_CS0_N")
		)
	)
	(footprint ""
		(layer "F.Cu")
		(at 109.165136 -119.46001 90)
		(property "Reference" "R1492"
			(at 0 0 90)
			(layer "F.SilkS")
			(hide yes)
			(effects
				(font
					(size 1.27 1.27)
				)
			)
		)
		(property "Value" ""
			(at 0 0 90)
			(layer "F.Fab")
			(effects
				(font
					(size 1.27 1.27)
				)
			)
		)
		(duplicate_pad_numbers_are_jumpers no)
		(fp_line
			(start 0.7874 -0.4064)
			(end 0.7874 0.4064)
			(stroke
				(width 0.1524)
				(type default)
			)
			(layer "F.SilkS")
		)
		(fp_line
			(start -0.7874 -0.4064)
			(end 0.7874 -0.4064)
			(stroke
				(width 0.1524)
				(type default)
			)
			(layer "F.SilkS")
		)
		(fp_line
			(start 0.7874 0.4064)
			(end -0.7874 0.4064)
			(stroke
				(width 0.1524)
				(type default)
			)
			(layer "F.SilkS")
		)
		(fp_line
			(start -0.7874 0.4064)
			(end -0.7874 -0.4064)
			(stroke
				(width 0.1524)
				(type default)
			)
			(layer "F.SilkS")
		)
		(fp_line
			(start -0.12065 -0.305054)
			(end -0.12065 -0.2794)
			(stroke
				(width 0.1)
				(type default)
			)
			(layer "F.Fab")
		)
		(fp_line
			(start -0.67945 -0.305054)
			(end -0.12065 -0.305054)
			(stroke
				(width 0.1)
				(type default)
			)
			(layer "F.Fab")
		)
		(fp_line
			(start 0.67945 -0.3048)
			(end 0.67945 0.3048)
			(stroke
				(width 0.1)
				(type default)
			)
			(layer "F.Fab")
		)
		(fp_line
			(start 0.12065 -0.3048)
			(end 0.67945 -0.3048)
			(stroke
				(width 0.1)
				(type default)
			)
			(layer "F.Fab")
		)
		(fp_line
			(start 0.12065 -0.2794)
			(end 0.12065 -0.3048)
			(stroke
				(width 0.1)
				(type default)
			)
			(layer "F.Fab")
		)
		(fp_line
			(start -0.12065 -0.2794)
			(end 0.12065 -0.2794)
			(stroke
				(width 0.1)
				(type default)
			)
			(layer "F.Fab")
		)
		(fp_line
			(start 0.120396 0.2794)
			(end -0.12065 0.2794)
			(stroke
				(width 0.1)
				(type default)
			)
			(layer "F.Fab")
		)
		(fp_line
			(start -0.12065 0.2794)
			(end -0.12065 0.3048)
			(stroke
				(width 0.1)
				(type default)
			)
			(layer "F.Fab")
		)
		(fp_line
			(start 0.67945 0.3048)
			(end 0.120396 0.3048)
			(stroke
				(width 0.1)
				(type default)
			)
			(layer "F.Fab")
		)
		(fp_line
			(start 0.120396 0.3048)
			(end 0.120396 0.2794)
			(stroke
				(width 0.1)
				(type default)
			)
			(layer "F.Fab")
		)
		(fp_line
			(start -0.12065 0.3048)
			(end -0.67945 0.3048)
			(stroke
				(width 0.1)
				(type default)
			)
			(layer "F.Fab")
		)
		(fp_line
			(start -0.67945 0.3048)
			(end -0.67945 -0.305054)
			(stroke
				(width 0.1)
				(type default)
			)
			(layer "F.Fab")
		)
		(pad "1" smd circle
			(at -0.40005 0 90)
			(size 0 0)
			(layers "F.Cu" "F.Mask" "F.Paste")
			(net "P3V3_AUX")
		)
		(pad "2" smd circle
			(at 0.40005 0 90)
			(size 0 0)
			(layers "F.Cu" "F.Mask" "F.Paste")
			(net "PWRGD_P3V3_EN_N")
		)
	)
	(footprint ""
		(layer "F.Cu")
		(at 152.97912 -23.284942 -90)
		(property "Reference" "R6014"
			(at 0 0 270)
			(layer "F.SilkS")
			(hide yes)
			(effects
				(font
					(size 1.27 1.27)
				)
			)
		)
		(property "Value" ""
			(at 0 0 270)
			(layer "F.Fab")
			(effects
				(font
					(size 1.27 1.27)
				)
			)
		)
		(duplicate_pad_numbers_are_jumpers no)
		(fp_line
			(start -0.7874 0.4064)
			(end -0.7874 -0.4064)
			(stroke
				(width 0.1524)
				(type default)
			)
			(layer "F.SilkS")
		)
		(fp_line
			(start 0.7874 0.4064)
			(end -0.7874 0.4064)
			(stroke
				(width 0.1524)
				(type default)
			)
			(layer "F.SilkS")
		)
		(fp_line
			(start -0.7874 -0.4064)
			(end 0.7874 -0.4064)
			(stroke
				(width 0.1524)
				(type default)
			)
			(layer "F.SilkS")
		)
		(fp_line
			(start 0.7874 -0.4064)
			(end 0.7874 0.4064)
			(stroke
				(width 0.1524)
				(type default)
			)
			(layer "F.SilkS")
		)
		(fp_line
			(start -0.67945 0.3048)
			(end -0.67945 -0.305054)
			(stroke
				(width 0.1)
				(type default)
			)
			(layer "F.Fab")
		)
		(fp_line
			(start -0.12065 0.3048)
			(end -0.67945 0.3048)
			(stroke
				(width 0.1)
				(type default)
			)
			(layer "F.Fab")
		)
		(fp_line
			(start 0.120396 0.3048)
			(end 0.120396 0.2794)
			(stroke
				(width 0.1)
				(type default)
			)
			(layer "F.Fab")
		)
		(fp_line
			(start 0.67945 0.3048)
			(end 0.120396 0.3048)
			(stroke
				(width 0.1)
				(type default)
			)
			(layer "F.Fab")
		)
		(fp_line
			(start -0.12065 0.2794)
			(end -0.12065 0.3048)
			(stroke
				(width 0.1)
				(type default)
			)
			(layer "F.Fab")
		)
		(fp_line
			(start 0.120396 0.2794)
			(end -0.12065 0.2794)
			(stroke
				(width 0.1)
				(type default)
			)
			(layer "F.Fab")
		)
		(fp_line
			(start -0.12065 -0.2794)
			(end 0.12065 -0.2794)
			(stroke
				(width 0.1)
				(type default)
			)
			(layer "F.Fab")
		)
		(fp_line
			(start 0.12065 -0.2794)
			(end 0.12065 -0.3048)
			(stroke
				(width 0.1)
				(type default)
			)
			(layer "F.Fab")
		)
		(fp_line
			(start 0.12065 -0.3048)
			(end 0.67945 -0.3048)
			(stroke
				(width 0.1)
				(type default)
			)
			(layer "F.Fab")
		)
		(fp_line
			(start 0.67945 -0.3048)
			(end 0.67945 0.3048)
			(stroke
				(width 0.1)
				(type default)
			)
			(layer "F.Fab")
		)
		(fp_line
			(start -0.67945 -0.305054)
			(end -0.12065 -0.305054)
			(stroke
				(width 0.1)
				(type default)
			)
			(layer "F.Fab")
		)
		(fp_line
			(start -0.12065 -0.305054)
			(end -0.12065 -0.2794)
			(stroke
				(width 0.1)
				(type default)
			)
			(layer "F.Fab")
		)
		(pad "1" smd circle
			(at -0.40005 0 270)
			(size 0 0)
			(layers "F.Cu" "F.Mask" "F.Paste")
			(net "SGPIO_SCM_DI_<1>")
		)
		(pad "2" smd circle
			(at 0.40005 0 270)
			(size 0 0)
			(layers "F.Cu" "F.Mask" "F.Paste")
			(net "SGPIO_SCM_DI_R_<1>")
		)
	)
	(footprint ""
		(layer "F.Cu")
		(at 205.232 -129.032 180)
		(property "Reference" "R496"
			(at 0 0 180)
			(layer "F.SilkS")
			(hide yes)
			(effects
				(font
					(size 1.27 1.27)
				)
			)
		)
		(property "Value" ""
			(at 0 0 180)
			(layer "F.Fab")
			(effects
				(font
					(size 1.27 1.27)
				)
			)
		)
		(duplicate_pad_numbers_are_jumpers no)
		(fp_line
			(start 0.7874 0.4064)
			(end -0.7874 0.4064)
			(stroke
				(width 0.1524)
				(type default)
			)
			(layer "F.SilkS")
		)
		(fp_line
			(start 0.7874 -0.4064)
			(end 0.7874 0.4064)
			(stroke
				(width 0.1524)
				(type default)
			)
			(layer "F.SilkS")
		)
		(fp_line
			(start -0.7874 0.4064)
			(end -0.7874 -0.4064)
			(stroke
				(width 0.1524)
				(type default)
			)
			(layer "F.SilkS")
		)
		(fp_line
			(start -0.7874 -0.4064)
			(end 0.7874 -0.4064)
			(stroke
				(width 0.1524)
				(type default)
			)
			(layer "F.SilkS")
		)
		(fp_line
			(start 0.67945 0.3048)
			(end 0.120396 0.3048)
			(stroke
				(width 0.1)
				(type default)
			)
			(layer "F.Fab")
		)
		(fp_line
			(start 0.67945 -0.3048)
			(end 0.67945 0.3048)
			(stroke
				(width 0.1)
				(type default)
			)
			(layer "F.Fab")
		)
		(fp_line
			(start 0.12065 -0.2794)
			(end 0.12065 -0.3048)
			(stroke
				(width 0.1)
				(type default)
			)
			(layer "F.Fab")
		)
		(fp_line
			(start 0.12065 -0.3048)
			(end 0.67945 -0.3048)
			(stroke
				(width 0.1)
				(type default)
			)
			(layer "F.Fab")
		)
		(fp_line
			(start 0.120396 0.3048)
			(end 0.120396 0.2794)
			(stroke
				(width 0.1)
				(type default)
			)
			(layer "F.Fab")
		)
		(fp_line
			(start 0.120396 0.2794)
			(end -0.12065 0.2794)
			(stroke
				(width 0.1)
				(type default)
			)
			(layer "F.Fab")
		)
		(fp_line
			(start -0.12065 0.3048)
			(end -0.67945 0.3048)
			(stroke
				(width 0.1)
				(type default)
			)
			(layer "F.Fab")
		)
		(fp_line
			(start -0.12065 0.2794)
			(end -0.12065 0.3048)
			(stroke
				(width 0.1)
				(type default)
			)
			(layer "F.Fab")
		)
		(fp_line
			(start -0.12065 -0.2794)
			(end 0.12065 -0.2794)
			(stroke
				(width 0.1)
				(type default)
			)
			(layer "F.Fab")
		)
		(fp_line
			(start -0.12065 -0.305054)
			(end -0.12065 -0.2794)
			(stroke
				(width 0.1)
				(type default)
			)
			(layer "F.Fab")
		)
		(fp_line
			(start -0.67945 0.3048)
			(end -0.67945 -0.305054)
			(stroke
				(width 0.1)
				(type default)
			)
			(layer "F.Fab")
		)
		(fp_line
			(start -0.67945 -0.305054)
			(end -0.12065 -0.305054)
			(stroke
				(width 0.1)
				(type default)
			)
			(layer "F.Fab")
		)
		(pad "1" smd circle
			(at -0.40005 0 180)
			(size 0 0)
			(layers "F.Cu" "F.Mask" "F.Paste")
			(net "P3V3_AUX")
		)
		(pad "2" smd circle
			(at 0.40005 0 180)
			(size 0 0)
			(layers "F.Cu" "F.Mask" "F.Paste")
			(net "SW_P3V3_EN")
		)
	)
	(footprint ""
		(layer "F.Cu")
		(at 137.033762 -151.616664 -90)
		(property "Reference" "PR336"
			(at 0 0 270)
			(layer "F.SilkS")
			(hide yes)
			(effects
				(font
					(size 1.27 1.27)
				)
			)
		)
		(property "Value" ""
			(at 0 0 270)
			(layer "F.Fab")
			(effects
				(font
					(size 1.27 1.27)
				)
			)
		)
		(duplicate_pad_numbers_are_jumpers no)
		(fp_line
			(start -0.7874 0.4064)
			(end -0.7874 -0.4064)
			(stroke
				(width 0.1524)
				(type default)
			)
			(layer "F.SilkS")
		)
		(fp_line
			(start 0.7874 0.4064)
			(end -0.7874 0.4064)
			(stroke
				(width 0.1524)
				(type default)
			)
			(layer "F.SilkS")
		)
		(fp_line
			(start -0.7874 -0.4064)
			(end 0.7874 -0.4064)
			(stroke
				(width 0.1524)
				(type default)
			)
			(layer "F.SilkS")
		)
		(fp_line
			(start 0.7874 -0.4064)
			(end 0.7874 0.4064)
			(stroke
				(width 0.1524)
				(type default)
			)
			(layer "F.SilkS")
		)
		(fp_line
			(start -0.67945 0.3048)
			(end -0.67945 -0.305054)
			(stroke
				(width 0.1)
				(type default)
			)
			(layer "F.Fab")
		)
		(fp_line
			(start -0.12065 0.3048)
			(end -0.67945 0.3048)
			(stroke
				(width 0.1)
				(type default)
			)
			(layer "F.Fab")
		)
		(fp_line
			(start 0.120396 0.3048)
			(end 0.120396 0.2794)
			(stroke
				(width 0.1)
				(type default)
			)
			(layer "F.Fab")
		)
		(fp_line
			(start 0.67945 0.3048)
			(end 0.120396 0.3048)
			(stroke
				(width 0.1)
				(type default)
			)
			(layer "F.Fab")
		)
		(fp_line
			(start -0.12065 0.2794)
			(end -0.12065 0.3048)
			(stroke
				(width 0.1)
				(type default)
			)
			(layer "F.Fab")
		)
		(fp_line
			(start 0.120396 0.2794)
			(end -0.12065 0.2794)
			(stroke
				(width 0.1)
				(type default)
			)
			(layer "F.Fab")
		)
		(fp_line
			(start -0.12065 -0.2794)
			(end 0.12065 -0.2794)
			(stroke
				(width 0.1)
				(type default)
			)
			(layer "F.Fab")
		)
		(fp_line
			(start 0.12065 -0.2794)
			(end 0.12065 -0.3048)
			(stroke
				(width 0.1)
				(type default)
			)
			(layer "F.Fab")
		)
		(fp_line
			(start 0.12065 -0.3048)
			(end 0.67945 -0.3048)
			(stroke
				(width 0.1)
				(type default)
			)
			(layer "F.Fab")
		)
		(fp_line
			(start 0.67945 -0.3048)
			(end 0.67945 0.3048)
			(stroke
				(width 0.1)
				(type default)
			)
			(layer "F.Fab")
		)
		(fp_line
			(start -0.67945 -0.305054)
			(end -0.12065 -0.305054)
			(stroke
				(width 0.1)
				(type default)
			)
			(layer "F.Fab")
		)
		(fp_line
			(start -0.12065 -0.305054)
			(end -0.12065 -0.2794)
			(stroke
				(width 0.1)
				(type default)
			)
			(layer "F.Fab")
		)
		(pad "1" smd circle
			(at -0.40005 0 270)
			(size 0 0)
			(layers "F.Cu" "F.Mask" "F.Paste")
			(net "PVDDCR_CPU0_P1_PVCC")
		)
		(pad "2" smd circle
			(at 0.40005 0 270)
			(size 0 0)
			(layers "F.Cu" "F.Mask" "F.Paste")
			(net "P3V3_AUX")
		)
	)
)
